FILE_TYPE = CONNECTIVITY;
{Allegro Design Entry HDL 17.2-2016 S081 (4005846) 1/11/2022}
"PAGE_NUMBER" = 281;
0"NC";
END.
